# S9S_MB_2U (Grand Teton) — schematic netlist excerpt (pin names and nets, part order shuffled) for the footprints in the layout excerpt that follows; sources: Cadence DE-HDL packaged netlist, KiCad conversion of 03242023_DA0F0TMBIJ0_F0T_Motherboard_J_brd_V01_OCP.brd

R979  Q_RES  560 1% CHIP  pkg 0402LF  page 236 : A = P3V3_AUX ; B = SMB_S3M_CPU0_3V3AUX_SDA
R1026  Q_RES  1K 1% CHIP  pkg 0402LF  page 182 : A = JTAG_DBP_PMODE ; B = P1V05_PCH_AUX

(kicad_pcb
	(version 20260206)
	(generator "pcbnew")
	(generator_version "10.0")
	(general
		(thickness 1.6)
		(legacy_teardrops no)
	)
	(paper "A4")
	(title_block
		(title "03242023_DA0F0TMBIJ0_F0T_Motherboard_J_brd_V01_OCP.brd")
		(comment 1 "Grand Teton / footprints 3117-3118 of 6105")
	)
	(layers
		(0 "F.Cu" signal "TOP")
		(4 "In1.Cu" signal "GND")
		(6 "In2.Cu" signal "IN1")
		(8 "In3.Cu" signal "GND1")
		(10 "In4.Cu" signal "IN2")
		(12 "In5.Cu" signal "GND2")
		(14 "In6.Cu" signal "IN3")
		(16 "In7.Cu" signal "GND3")
		(18 "In8.Cu" signal "VCC")
		(20 "In9.Cu" signal "VCC1")
		(22 "In10.Cu" signal "GND4")
		(24 "In11.Cu" signal "IN4")
		(26 "In12.Cu" signal "GND5")
		(28 "In13.Cu" signal "IN5")
		(30 "In14.Cu" signal "GND6")
		(32 "In15.Cu" signal "IN6")
		(34 "In16.Cu" signal "GND7")
		(2 "B.Cu" signal "BOTTOM")
		(9 "F.Adhes" user "F.Adhesive")
		(11 "B.Adhes" user "B.Adhesive")
		(13 "F.Paste" user "Package Geometry/Pastemask Top")
		(15 "B.Paste" user "Package Geometry/Pastemask Bottom")
		(5 "F.SilkS" user "Ref Des/Silkscreen Top")
		(7 "B.SilkS" user "Ref Des/Silkscreen Bottom")
		(1 "F.Mask" user "Board Geometry/Soldermask Top")
		(3 "B.Mask" user "Board Geometry/Soldermask Bottom")
		(17 "Dwgs.User" user "User.Drawings")
		(19 "Cmts.User" user "User.Comments")
		(21 "Eco1.User" user "User.Eco1")
		(23 "Eco2.User" user "User.Eco2")
		(25 "Edge.Cuts" user "Board Geometry/Outline")
		(27 "Margin" user)
		(31 "F.CrtYd" user "Package Geometry/Place Bound Top")
		(29 "B.CrtYd" user "Package Geometry/Place Bound Bottom")
		(35 "F.Fab" user "Ref Des/Assembly Top")
		(33 "B.Fab" user "Ref Des/Assembly Bottom")
	)
	(footprint ""
		(layer "F.Cu")
		(at 392.10488 -148.808948 90)
		(property "Reference" "R979"
			(at 0 0 90)
			(layer "F.SilkS")
			(hide yes)
			(effects
				(font
					(size 1.27 1.27)
				)
			)
		)
		(property "Value" ""
			(at 0 0 90)
			(layer "F.Fab")
			(effects
				(font
					(size 1.27 1.27)
				)
			)
		)
		(duplicate_pad_numbers_are_jumpers no)
		(fp_line
			(start 0.7874 -0.4064)
			(end 0.7874 0.4064)
			(stroke
				(width 0.1524)
				(type default)
			)
			(layer "F.SilkS")
		)
		(fp_line
			(start -0.7874 -0.4064)
			(end 0.7874 -0.4064)
			(stroke
				(width 0.1524)
				(type default)
			)
			(layer "F.SilkS")
		)
		(fp_line
			(start 0.7874 0.4064)
			(end -0.7874 0.4064)
			(stroke
				(width 0.1524)
				(type default)
			)
			(layer "F.SilkS")
		)
		(fp_line
			(start -0.7874 0.4064)
			(end -0.7874 -0.4064)
			(stroke
				(width 0.1524)
				(type default)
			)
			(layer "F.SilkS")
		)
		(fp_line
			(start -0.12065 -0.305054)
			(end -0.12065 -0.2794)
			(stroke
				(width 0.1)
				(type default)
			)
			(layer "F.Fab")
		)
		(fp_line
			(start -0.67945 -0.305054)
			(end -0.12065 -0.305054)
			(stroke
				(width 0.1)
				(type default)
			)
			(layer "F.Fab")
		)
		(fp_line
			(start 0.67945 -0.3048)
			(end 0.67945 0.3048)
			(stroke
				(width 0.1)
				(type default)
			)
			(layer "F.Fab")
		)
		(fp_line
			(start 0.12065 -0.3048)
			(end 0.67945 -0.3048)
			(stroke
				(width 0.1)
				(type default)
			)
			(layer "F.Fab")
		)
		(fp_line
			(start 0.12065 -0.2794)
			(end 0.12065 -0.3048)
			(stroke
				(width 0.1)
				(type default)
			)
			(layer "F.Fab")
		)
		(fp_line
			(start -0.12065 -0.2794)
			(end 0.12065 -0.2794)
			(stroke
				(width 0.1)
				(type default)
			)
			(layer "F.Fab")
		)
		(fp_line
			(start 0.120396 0.2794)
			(end -0.12065 0.2794)
			(stroke
				(width 0.1)
				(type default)
			)
			(layer "F.Fab")
		)
		(fp_line
			(start -0.12065 0.2794)
			(end -0.12065 0.3048)
			(stroke
				(width 0.1)
				(type default)
			)
			(layer "F.Fab")
		)
		(fp_line
			(start 0.67945 0.3048)
			(end 0.120396 0.3048)
			(stroke
				(width 0.1)
				(type default)
			)
			(layer "F.Fab")
		)
		(fp_line
			(start 0.120396 0.3048)
			(end 0.120396 0.2794)
			(stroke
				(width 0.1)
				(type default)
			)
			(layer "F.Fab")
		)
		(fp_line
			(start -0.12065 0.3048)
			(end -0.67945 0.3048)
			(stroke
				(width 0.1)
				(type default)
			)
			(layer "F.Fab")
		)
		(fp_line
			(start -0.67945 0.3048)
			(end -0.67945 -0.305054)
			(stroke
				(width 0.1)
				(type default)
			)
			(layer "F.Fab")
		)
		(pad "1" smd circle
			(at -0.40005 0 90)
			(size 0 0)
			(layers "F.Cu" "F.Mask" "F.Paste")
			(net "P3V3_AUX")
		)
		(pad "2" smd circle
			(at 0.40005 0 90)
			(size 0 0)
			(layers "F.Cu" "F.Mask" "F.Paste")
			(net "SMB_S3M_CPU0_3V3AUX_SDA")
		)
	)
	(footprint ""
		(layer "F.Cu")
		(at 385.716272 -63.423292 180)
		(property "Reference" "R1026"
			(at 0 0 180)
			(layer "F.SilkS")
			(hide yes)
			(effects
				(font
					(size 1.27 1.27)
				)
			)
		)
		(property "Value" ""
			(at 0 0 180)
			(layer "F.Fab")
			(effects
				(font
					(size 1.27 1.27)
				)
			)
		)
		(duplicate_pad_numbers_are_jumpers no)
		(fp_line
			(start 0.7874 0.4064)
			(end -0.7874 0.4064)
			(stroke
				(width 0.1524)
				(type default)
			)
			(layer "F.SilkS")
		)
		(fp_line
			(start 0.7874 -0.4064)
			(end 0.7874 0.4064)
			(stroke
				(width 0.1524)
				(type default)
			)
			(layer "F.SilkS")
		)
		(fp_line
			(start -0.7874 0.4064)
			(end -0.7874 -0.4064)
			(stroke
				(width 0.1524)
				(type default)
			)
			(layer "F.SilkS")
		)
		(fp_line
			(start -0.7874 -0.4064)
			(end 0.7874 -0.4064)
			(stroke
				(width 0.1524)
				(type default)
			)
			(layer "F.SilkS")
		)
		(fp_line
			(start 0.67945 0.3048)
			(end 0.120396 0.3048)
			(stroke
				(width 0.1)
				(type default)
			)
			(layer "F.Fab")
		)
		(fp_line
			(start 0.67945 -0.3048)
			(end 0.67945 0.3048)
			(stroke
				(width 0.1)
				(type default)
			)
			(layer "F.Fab")
		)
		(fp_line
			(start 0.12065 -0.2794)
			(end 0.12065 -0.3048)
			(stroke
				(width 0.1)
				(type default)
			)
			(layer "F.Fab")
		)
		(fp_line
			(start 0.12065 -0.3048)
			(end 0.67945 -0.3048)
			(stroke
				(width 0.1)
				(type default)
			)
			(layer "F.Fab")
		)
		(fp_line
			(start 0.120396 0.3048)
			(end 0.120396 0.2794)
			(stroke
				(width 0.1)
				(type default)
			)
			(layer "F.Fab")
		)
		(fp_line
			(start 0.120396 0.2794)
			(end -0.12065 0.2794)
			(stroke
				(width 0.1)
				(type default)
			)
			(layer "F.Fab")
		)
		(fp_line
			(start -0.12065 0.3048)
			(end -0.67945 0.3048)
			(stroke
				(width 0.1)
				(type default)
			)
			(layer "F.Fab")
		)
		(fp_line
			(start -0.12065 0.2794)
			(end -0.12065 0.3048)
			(stroke
				(width 0.1)
				(type default)
			)
			(layer "F.Fab")
		)
		(fp_line
			(start -0.12065 -0.2794)
			(end 0.12065 -0.2794)
			(stroke
				(width 0.1)
				(type default)
			)
			(layer "F.Fab")
		)
		(fp_line
			(start -0.12065 -0.305054)
			(end -0.12065 -0.2794)
			(stroke
				(width 0.1)
				(type default)
			)
			(layer "F.Fab")
		)
		(fp_line
			(start -0.67945 0.3048)
			(end -0.67945 -0.305054)
			(stroke
				(width 0.1)
				(type default)
			)
			(layer "F.Fab")
		)
		(fp_line
			(start -0.67945 -0.305054)
			(end -0.12065 -0.305054)
			(stroke
				(width 0.1)
				(type default)
			)
			(layer "F.Fab")
		)
		(pad "1" smd circle
			(at -0.40005 0 180)
			(size 0 0)
			(layers "F.Cu" "F.Mask" "F.Paste")
			(net "JTAG_DBP_PMODE")
		)
		(pad "2" smd circle
			(at 0.40005 0 180)
			(size 0 0)
			(layers "F.Cu" "F.Mask" "F.Paste")
			(net "P1V05_PCH_AUX")
		)
	)
)
